(kicad_pcb
	(version 20260206)
	(generator "pcbnew")
	(generator_version "10.0")
	(general
		(thickness 1.6)
		(legacy_teardrops no)
	)
	(paper "A4")
	(title_block
		(title "Wiwynn_Tioga_Pass_MB.brd")
		(comment 1 "Tioga Pass / footprints 3811-3817 of 4770")
	)
	(layers
		(0 "F.Cu" signal "TOP")
		(4 "In1.Cu" signal "L2GND")
		(6 "In2.Cu" signal "L3")
		(8 "In3.Cu" signal "L4GND")
		(10 "In4.Cu" signal "L5")
		(12 "In5.Cu" signal "L6GND")
		(14 "In6.Cu" signal "L7VCC")
		(16 "In7.Cu" signal "L8VCC")
		(18 "In8.Cu" signal "L9GND")
		(20 "In9.Cu" signal "L10")
		(22 "In10.Cu" signal "L11GND")
		(24 "In11.Cu" signal "L12")
		(26 "In12.Cu" signal "L13GND")
		(2 "B.Cu" signal "BOTTOM")
		(9 "F.Adhes" user "F.Adhesive")
		(11 "B.Adhes" user "B.Adhesive")
		(13 "F.Paste" user "Package Geometry/Pastemask Top")
		(15 "B.Paste" user "Package Geometry/Pastemask Bottom")
		(5 "F.SilkS" user "Ref Des/Silkscreen Top")
		(7 "B.SilkS" user "Ref Des/Silkscreen Bottom")
		(1 "F.Mask" user "Board Geometry/Soldermask Top")
		(3 "B.Mask" user "Board Geometry/Soldermask Bottom")
		(17 "Dwgs.User" user "User.Drawings")
		(19 "Cmts.User" user "User.Comments")
		(21 "Eco1.User" user "User.Eco1")
		(23 "Eco2.User" user "User.Eco2")
		(25 "Edge.Cuts" user "Board Geometry/Outline")
		(27 "Margin" user)
		(31 "F.CrtYd" user "Package Geometry/Place Bound Top")
		(29 "B.CrtYd" user "Package Geometry/Place Bound Bottom")
		(35 "F.Fab" user "Ref Des/Assembly Top")
		(33 "B.Fab" user "Ref Des/Assembly Bottom")
	)
	(footprint ""
		(layer "B.Cu")
		(at 331.139038 -37.815266)
		(property "Reference" "C4T2"
			(at 0 0 0)
			(layer "B.SilkS")
			(hide yes)
			(effects
				(font
					(size 1.27 1.27)
				)
				(justify mirror)
			)
		)
		(property "Value" ""
			(at 0 0 0)
			(layer "B.Fab")
			(effects
				(font
					(size 1.27 1.27)
				)
				(justify mirror)
			)
		)
		(duplicate_pad_numbers_are_jumpers no)
		(fp_poly
			(pts
				(xy -0.3048 -0.1016) (xy -0.3048 0.9906) (xy 0.3048 0.9906) (xy 0.3048 -0.1016)
			)
			(stroke
				(width 0)
				(type default)
			)
			(fill no)
			(layer "B.CrtYd")
		)
		(fp_line
			(start -0.3048 -0.1016)
			(end 0.3048 -0.1016)
			(stroke
				(width 0.1)
				(type default)
			)
			(layer "B.Fab")
		)
		(fp_line
			(start -0.3048 0.9906)
			(end -0.3048 -0.1016)
			(stroke
				(width 0.1)
				(type default)
			)
			(layer "B.Fab")
		)
		(fp_line
			(start 0.3048 -0.1016)
			(end 0.3048 0.9906)
			(stroke
				(width 0.1)
				(type default)
			)
			(layer "B.Fab")
		)
		(fp_line
			(start 0.3048 0.9906)
			(end -0.3048 0.9906)
			(stroke
				(width 0.1)
				(type default)
			)
			(layer "B.Fab")
		)
		(pad "1" smd rect
			(at 0 0 180)
			(size 0.508 0.508)
			(layers "B.Cu" "B.Mask" "B.Paste")
			(net "P1V8_MCP_CPU0")
		)
		(pad "2" smd rect
			(at 0 0.889 180)
			(size 0.508 0.508)
			(layers "B.Cu" "B.Mask" "B.Paste")
			(net "GND")
		)
		(zone
			(layer "B.Cu")
			(hatch none 0.5)
			(connect_pads
				(clearance 0)
			)
			(min_thickness 0.25)
			(keepout
				(tracks allowed)
				(vias not_allowed)
				(pads allowed)
				(copperpour not_allowed)
				(footprints allowed)
			)
			(placement
				(enabled no)
				(sheetname "")
			)
			(fill
				(thermal_gap 0.5)
				(thermal_bridge_width 0.5)
				(island_removal_mode 0)
			)
			(polygon
				(pts
					(xy 331.393038 -37.561266) (xy 330.885038 -37.561266) (xy 330.885038 -37.180266) (xy 331.393038 -37.180266)
				)
			)
		)
		(zone
			(layer "B.Cu")
			(hatch none 0.5)
			(connect_pads
				(clearance 0)
			)
			(min_thickness 0.25)
			(keepout
				(tracks not_allowed)
				(vias allowed)
				(pads allowed)
				(copperpour not_allowed)
				(footprints allowed)
			)
			(placement
				(enabled no)
				(sheetname "")
			)
			(fill
				(thermal_gap 0.5)
				(thermal_bridge_width 0.5)
				(island_removal_mode 0)
			)
			(polygon
				(pts
					(xy 331.393038 -37.180266) (xy 330.885038 -37.180266) (xy 330.885038 -37.561266) (xy 331.393038 -37.561266)
				)
			)
		)
	)
	(footprint ""
		(layer "B.Cu")
		(at 418.846 -24.765 90)
		(property "Reference" "L25W3"
			(at 0 0 90)
			(layer "B.SilkS")
			(hide yes)
			(effects
				(font
					(size 1.27 1.27)
				)
				(justify mirror)
			)
		)
		(property "Value" "*"
			(at -0.0254 -2.8829 90)
			(unlocked yes)
			(layer "B.Fab")
			(hide yes)
			(effects
				(font
					(size 1.27 1.016)
					(thickness 0.1524)
				)
				(justify mirror)
			)
		)
		(property "Device Type" "IND-68NH-15-GP_DISCRET-GC1-INDA"
			(at -0.0254 -4.4069 90)
			(unlocked yes)
			(layer "B.Fab")
			(hide yes)
			(effects
				(font
					(size 1.27 1.016)
					(thickness 0.1524)
				)
				(justify mirror)
			)
		)
		(duplicate_pad_numbers_are_jumpers no)
		(fp_line
			(start -0.254 0)
			(end 0.254 0)
			(stroke
				(width 0.2032)
				(type default)
			)
			(layer "B.SilkS")
		)
		(fp_rect
			(start 0.5842 1.3335)
			(end -0.5842 -1.3335)
			(stroke
				(width 0)
				(type default)
			)
			(fill no)
			(layer "B.CrtYd")
		)
		(fp_rect
			(start 0.5842 1.3335)
			(end -0.5842 -1.3335)
			(stroke
				(width 0)
				(type default)
			)
			(fill no)
			(layer "B.Fab")
		)
		(pad "1" smd custom
			(at 0 -0.762 270)
			(size 0.2159 0.2159)
			(layers "B.Cu" "B.Mask" "B.Paste")
			(net "BMC_VGA_RED")
			(options
				(clearance outline)
				(anchor circle)
			)
			(primitives
				(gr_poly
					(pts
						(arc
							(start -0.3302 0.4318)
							(mid -0.402042 0.402042)
							(end -0.4318 0.3302)
						)
						(arc
							(start -0.4318 -0.3302)
							(mid -0.402042 -0.402042)
							(end -0.3302 -0.4318)
						)
						(arc
							(start 0.3302 -0.4318)
							(mid 0.402042 -0.402042)
							(end 0.4318 -0.3302)
						)
						(arc
							(start 0.4318 0.3302)
							(mid 0.402042 0.402042)
							(end 0.3302 0.4318)
						)
					)
					(width 0)
					(fill yes)
				)
			)
		)
		(pad "2" smd custom
			(at 0 0.762 270)
			(size 0.2159 0.2159)
			(layers "B.Cu" "B.Mask" "B.Paste")
			(net "V_IO_R_J")
			(options
				(clearance outline)
				(anchor circle)
			)
			(primitives
				(gr_poly
					(pts
						(arc
							(start -0.3302 0.4318)
							(mid -0.402042 0.402042)
							(end -0.4318 0.3302)
						)
						(arc
							(start -0.4318 -0.3302)
							(mid -0.402042 -0.402042)
							(end -0.3302 -0.4318)
						)
						(arc
							(start 0.3302 -0.4318)
							(mid 0.402042 -0.402042)
							(end 0.4318 -0.3302)
						)
						(arc
							(start 0.4318 0.3302)
							(mid 0.402042 0.402042)
							(end 0.3302 0.4318)
						)
					)
					(width 0)
					(fill yes)
				)
			)
		)
	)
	(footprint ""
		(layer "B.Cu")
		(at 13.843 -89.154 90)
		(property "Reference" "R9N16"
			(at 0 0 90)
			(layer "B.SilkS")
			(hide yes)
			(effects
				(font
					(size 1.27 1.27)
				)
				(justify mirror)
			)
		)
		(property "Value" ""
			(at 0 0 90)
			(layer "B.Fab")
			(effects
				(font
					(size 1.27 1.27)
				)
				(justify mirror)
			)
		)
		(duplicate_pad_numbers_are_jumpers no)
		(fp_rect
			(start -0.2794 -0.1016)
			(end 0.2794 0.9906)
			(stroke
				(width 0)
				(type default)
			)
			(fill no)
			(layer "B.CrtYd")
		)
		(fp_line
			(start 0.2794 -0.1016)
			(end 0.2794 0.9906)
			(stroke
				(width 0.1)
				(type default)
			)
			(layer "B.Fab")
		)
		(fp_line
			(start -0.2794 -0.1016)
			(end 0.2794 -0.1016)
			(stroke
				(width 0.1)
				(type default)
			)
			(layer "B.Fab")
		)
		(fp_line
			(start 0.2794 0.9906)
			(end -0.2794 0.9906)
			(stroke
				(width 0.1)
				(type default)
			)
			(layer "B.Fab")
		)
		(fp_line
			(start -0.2794 0.9906)
			(end -0.2794 -0.1016)
			(stroke
				(width 0.1)
				(type default)
			)
			(layer "B.Fab")
		)
		(pad "1" smd rect
			(at 0 0 270)
			(size 0.508 0.508)
			(layers "B.Cu" "B.Mask" "B.Paste")
			(net "FM_PVCCIN_PVCCSA_CPU1_EN_LVC1")
		)
		(pad "2" smd rect
			(at 0 0.889 270)
			(size 0.508 0.508)
			(layers "B.Cu" "B.Mask" "B.Paste")
			(net "VR_PVCCIN_CPU1_VREN")
		)
		(zone
			(layer "B.Cu")
			(hatch none 0.5)
			(connect_pads
				(clearance 0)
			)
			(min_thickness 0.25)
			(keepout
				(tracks not_allowed)
				(vias allowed)
				(pads allowed)
				(copperpour not_allowed)
				(footprints allowed)
			)
			(placement
				(enabled no)
				(sheetname "")
			)
			(fill
				(thermal_gap 0.5)
				(thermal_bridge_width 0.5)
				(island_removal_mode 0)
			)
			(polygon
				(pts
					(xy 14.097 -88.9) (xy 14.478 -88.9) (xy 14.478 -89.408) (xy 14.097 -89.408)
				)
			)
		)
		(zone
			(layer "B.Cu")
			(hatch none 0.5)
			(connect_pads
				(clearance 0)
			)
			(min_thickness 0.25)
			(keepout
				(tracks allowed)
				(vias not_allowed)
				(pads allowed)
				(copperpour not_allowed)
				(footprints allowed)
			)
			(placement
				(enabled no)
				(sheetname "")
			)
			(fill
				(thermal_gap 0.5)
				(thermal_bridge_width 0.5)
				(island_removal_mode 0)
			)
			(polygon
				(pts
					(xy 14.097 -88.9) (xy 14.478 -88.9) (xy 14.478 -89.408) (xy 14.097 -89.408)
				)
			)
		)
	)
	(footprint ""
		(layer "B.Cu")
		(at 417.919916 -35.202368 -90)
		(property "Reference" "C25W24"
			(at 0.8382 -0.67818 270)
			(unlocked yes)
			(layer "B.SilkS")
			(effects
				(font
					(size 0.4064 0.254)
					(thickness 0.1524)
				)
				(justify left mirror)
			)
		)
		(property "Value" ""
			(at 0 0 90)
			(layer "B.Fab")
			(effects
				(font
					(size 1.27 1.27)
				)
				(justify mirror)
			)
		)
		(duplicate_pad_numbers_are_jumpers no)
		(fp_poly
			(pts
				(xy -0.3048 -0.1016) (xy -0.3048 0.9906) (xy 0.3048 0.9906) (xy 0.3048 -0.1016)
			)
			(stroke
				(width 0)
				(type default)
			)
			(fill no)
			(layer "B.CrtYd")
		)
		(fp_line
			(start -0.3048 0.9906)
			(end -0.3048 -0.1016)
			(stroke
				(width 0.1)
				(type default)
			)
			(layer "B.Fab")
		)
		(fp_line
			(start 0.3048 0.9906)
			(end -0.3048 0.9906)
			(stroke
				(width 0.1)
				(type default)
			)
			(layer "B.Fab")
		)
		(fp_line
			(start -0.3048 -0.1016)
			(end 0.3048 -0.1016)
			(stroke
				(width 0.1)
				(type default)
			)
			(layer "B.Fab")
		)
		(fp_line
			(start 0.3048 -0.1016)
			(end 0.3048 0.9906)
			(stroke
				(width 0.1)
				(type default)
			)
			(layer "B.Fab")
		)
		(pad "1" smd rect
			(at 0 0 90)
			(size 0.508 0.508)
			(layers "B.Cu" "B.Mask" "B.Paste")
			(net "P1V15_AUX_BMC")
		)
		(pad "2" smd rect
			(at 0 0.889 90)
			(size 0.508 0.508)
			(layers "B.Cu" "B.Mask" "B.Paste")
			(net "GND")
		)
		(zone
			(layer "B.Cu")
			(hatch none 0.5)
			(connect_pads
				(clearance 0)
			)
			(min_thickness 0.25)
			(keepout
				(tracks not_allowed)
				(vias allowed)
				(pads allowed)
				(copperpour not_allowed)
				(footprints allowed)
			)
			(placement
				(enabled no)
				(sheetname "")
			)
			(fill
				(thermal_gap 0.5)
				(thermal_bridge_width 0.5)
				(island_removal_mode 0)
			)
			(polygon
				(pts
					(xy 417.284916 -34.948368) (xy 417.284916 -35.456368) (xy 417.665916 -35.456368) (xy 417.665916 -34.948368)
				)
			)
		)
		(zone
			(layer "B.Cu")
			(hatch none 0.5)
			(connect_pads
				(clearance 0)
			)
			(min_thickness 0.25)
			(keepout
				(tracks allowed)
				(vias not_allowed)
				(pads allowed)
				(copperpour not_allowed)
				(footprints allowed)
			)
			(placement
				(enabled no)
				(sheetname "")
			)
			(fill
				(thermal_gap 0.5)
				(thermal_bridge_width 0.5)
				(island_removal_mode 0)
			)
			(polygon
				(pts
					(xy 417.665916 -34.948368) (xy 417.665916 -35.456368) (xy 417.284916 -35.456368) (xy 417.284916 -34.948368)
				)
			)
		)
	)
	(footprint ""
		(layer "B.Cu")
		(at 339.7504 -111.4044 180)
		(property "Reference" "R3N29"
			(at 0 0 0)
			(layer "B.SilkS")
			(hide yes)
			(effects
				(font
					(size 1.27 1.27)
				)
				(justify mirror)
			)
		)
		(property "Value" ""
			(at 0 0 0)
			(layer "B.Fab")
			(effects
				(font
					(size 1.27 1.27)
				)
				(justify mirror)
			)
		)
		(duplicate_pad_numbers_are_jumpers no)
		(fp_poly
			(pts
				(xy 0.2794 -0.1016) (xy -0.2794 -0.1016) (xy -0.2794 0.9906) (xy 0.2794 0.9906)
			)
			(stroke
				(width 0)
				(type default)
			)
			(fill no)
			(layer "B.CrtYd")
		)
		(fp_line
			(start 0.2794 0.9906)
			(end -0.2794 0.9906)
			(stroke
				(width 0.1)
				(type default)
			)
			(layer "B.Fab")
		)
		(fp_line
			(start 0.2794 -0.1016)
			(end 0.2794 0.9906)
			(stroke
				(width 0.1)
				(type default)
			)
			(layer "B.Fab")
		)
		(fp_line
			(start -0.2794 0.9906)
			(end -0.2794 -0.1016)
			(stroke
				(width 0.1)
				(type default)
			)
			(layer "B.Fab")
		)
		(fp_line
			(start -0.2794 -0.1016)
			(end 0.2794 -0.1016)
			(stroke
				(width 0.1)
				(type default)
			)
			(layer "B.Fab")
		)
		(pad "1" smd rect
			(at 0 0)
			(size 0.508 0.508)
			(layers "B.Cu" "B.Mask" "B.Paste")
			(net "VR_PVCCIOMCP_CPU0_XADDR1")
		)
		(pad "2" smd rect
			(at 0 0.889)
			(size 0.508 0.508)
			(layers "B.Cu" "B.Mask" "B.Paste")
			(net "GND")
		)
		(zone
			(layer "B.Cu")
			(hatch none 0.5)
			(connect_pads
				(clearance 0)
			)
			(min_thickness 0.25)
			(keepout
				(tracks not_allowed)
				(vias allowed)
				(pads allowed)
				(copperpour not_allowed)
				(footprints allowed)
			)
			(placement
				(enabled no)
				(sheetname "")
			)
			(fill
				(thermal_gap 0.5)
				(thermal_bridge_width 0.5)
				(island_removal_mode 0)
			)
			(polygon
				(pts
					(xy 339.4964 -112.0394) (xy 340.0044 -112.0394) (xy 340.0044 -111.6584) (xy 339.4964 -111.6584)
				)
			)
		)
		(zone
			(layer "B.Cu")
			(hatch none 0.5)
			(connect_pads
				(clearance 0)
			)
			(min_thickness 0.25)
			(keepout
				(tracks allowed)
				(vias not_allowed)
				(pads allowed)
				(copperpour not_allowed)
				(footprints allowed)
			)
			(placement
				(enabled no)
				(sheetname "")
			)
			(fill
				(thermal_gap 0.5)
				(thermal_bridge_width 0.5)
				(island_removal_mode 0)
			)
			(polygon
				(pts
					(xy 339.4964 -111.6584) (xy 340.0044 -111.6584) (xy 340.0044 -112.0394) (xy 339.4964 -112.0394)
				)
			)
		)
	)
	(footprint ""
		(layer "B.Cu")
		(at 171.059856 -128.850136)
		(property "Reference" "R5W2"
			(at 0.8382 -0.67818 0)
			(unlocked yes)
			(layer "B.SilkS")
			(effects
				(font
					(size 0.4064 0.254)
					(thickness 0.1524)
				)
				(justify left mirror)
			)
		)
		(property "Value" ""
			(at 0 0 0)
			(layer "B.Fab")
			(effects
				(font
					(size 1.27 1.27)
				)
				(justify mirror)
			)
		)
		(duplicate_pad_numbers_are_jumpers no)
		(fp_poly
			(pts
				(xy 0.2794 -0.1016) (xy -0.2794 -0.1016) (xy -0.2794 0.9906) (xy 0.2794 0.9906)
			)
			(stroke
				(width 0)
				(type default)
			)
			(fill no)
			(layer "B.CrtYd")
		)
		(fp_line
			(start -0.2794 -0.1016)
			(end 0.2794 -0.1016)
			(stroke
				(width 0.1)
				(type default)
			)
			(layer "B.Fab")
		)
		(fp_line
			(start -0.2794 0.9906)
			(end -0.2794 -0.1016)
			(stroke
				(width 0.1)
				(type default)
			)
			(layer "B.Fab")
		)
		(fp_line
			(start 0.2794 -0.1016)
			(end 0.2794 0.9906)
			(stroke
				(width 0.1)
				(type default)
			)
			(layer "B.Fab")
		)
		(fp_line
			(start 0.2794 0.9906)
			(end -0.2794 0.9906)
			(stroke
				(width 0.1)
				(type default)
			)
			(layer "B.Fab")
		)
		(pad "1" smd rect
			(at 0 0 180)
			(size 0.508 0.508)
			(layers "B.Cu" "B.Mask" "B.Paste")
			(net "P1V8_MCP_CPU1")
		)
		(pad "2" smd rect
			(at 0 0.889 180)
			(size 0.508 0.508)
			(layers "B.Cu" "B.Mask" "B.Paste")
			(net "JTAG_MCP_CPU1_TDI_R")
		)
		(zone
			(layer "B.Cu")
			(hatch none 0.5)
			(connect_pads
				(clearance 0)
			)
			(min_thickness 0.25)
			(keepout
				(tracks allowed)
				(vias not_allowed)
				(pads allowed)
				(copperpour not_allowed)
				(footprints allowed)
			)
			(placement
				(enabled no)
				(sheetname "")
			)
			(fill
				(thermal_gap 0.5)
				(thermal_bridge_width 0.5)
				(island_removal_mode 0)
			)
			(polygon
				(pts
					(xy 171.313856 -128.596136) (xy 170.805856 -128.596136) (xy 170.805856 -128.215136) (xy 171.313856 -128.215136)
				)
			)
		)
		(zone
			(layer "B.Cu")
			(hatch none 0.5)
			(connect_pads
				(clearance 0)
			)
			(min_thickness 0.25)
			(keepout
				(tracks not_allowed)
				(vias allowed)
				(pads allowed)
				(copperpour not_allowed)
				(footprints allowed)
			)
			(placement
				(enabled no)
				(sheetname "")
			)
			(fill
				(thermal_gap 0.5)
				(thermal_bridge_width 0.5)
				(island_removal_mode 0)
			)
			(polygon
				(pts
					(xy 171.313856 -128.215136) (xy 170.805856 -128.215136) (xy 170.805856 -128.596136) (xy 171.313856 -128.596136)
				)
			)
		)
	)
	(footprint ""
		(layer "B.Cu")
		(at 409.600146 -21.853652 -90)
		(property "Reference" "C9G15"
			(at 0 0 90)
			(layer "B.SilkS")
			(hide yes)
			(effects
				(font
					(size 1.27 1.27)
				)
				(justify mirror)
			)
		)
		(property "Value" ""
			(at 0 0 90)
			(layer "B.Fab")
			(effects
				(font
					(size 1.27 1.27)
				)
				(justify mirror)
			)
		)
		(duplicate_pad_numbers_are_jumpers no)
		(fp_poly
			(pts
				(xy -0.3048 -0.1016) (xy -0.3048 0.9906) (xy 0.3048 0.9906) (xy 0.3048 -0.1016)
			)
			(stroke
				(width 0)
				(type default)
			)
			(fill no)
			(layer "B.CrtYd")
		)
		(fp_line
			(start -0.3048 0.9906)
			(end -0.3048 -0.1016)
			(stroke
				(width 0.1)
				(type default)
			)
			(layer "B.Fab")
		)
		(fp_line
			(start 0.3048 0.9906)
			(end -0.3048 0.9906)
			(stroke
				(width 0.1)
				(type default)
			)
			(layer "B.Fab")
		)
		(fp_line
			(start -0.3048 -0.1016)
			(end 0.3048 -0.1016)
			(stroke
				(width 0.1)
				(type default)
			)
			(layer "B.Fab")
		)
		(fp_line
			(start 0.3048 -0.1016)
			(end 0.3048 0.9906)
			(stroke
				(width 0.1)
				(type default)
			)
			(layer "B.Fab")
		)
		(pad "1" smd rect
			(at 0 0 90)
			(size 0.508 0.508)
			(layers "B.Cu" "B.Mask" "B.Paste")
			(net "A_P5V_SCALED")
		)
		(pad "2" smd rect
			(at 0 0.889 90)
			(size 0.508 0.508)
			(layers "B.Cu" "B.Mask" "B.Paste")
			(net "GND")
		)
		(zone
			(layer "B.Cu")
			(hatch none 0.5)
			(connect_pads
				(clearance 0)
			)
			(min_thickness 0.25)
			(keepout
				(tracks not_allowed)
				(vias allowed)
				(pads allowed)
				(copperpour not_allowed)
				(footprints allowed)
			)
			(placement
				(enabled no)
				(sheetname "")
			)
			(fill
				(thermal_gap 0.5)
				(thermal_bridge_width 0.5)
				(island_removal_mode 0)
			)
			(polygon
				(pts
					(xy 408.965146 -21.599652) (xy 408.965146 -22.107652) (xy 409.346146 -22.107652) (xy 409.346146 -21.599652)
				)
			)
		)
		(zone
			(layer "B.Cu")
			(hatch none 0.5)
			(connect_pads
				(clearance 0)
			)
			(min_thickness 0.25)
			(keepout
				(tracks allowed)
				(vias not_allowed)
				(pads allowed)
				(copperpour not_allowed)
				(footprints allowed)
			)
			(placement
				(enabled no)
				(sheetname "")
			)
			(fill
				(thermal_gap 0.5)
				(thermal_bridge_width 0.5)
				(island_removal_mode 0)
			)
			(polygon
				(pts
					(xy 409.346146 -21.599652) (xy 409.346146 -22.107652) (xy 408.965146 -22.107652) (xy 408.965146 -21.599652)
				)
			)
		)
	)
)
